#ISCELL
  mstr_symbols cad_note *
  *
#ISCELL
  mstr_symbols intel_corp_bpage *
  *
#ISCELL
  mstr_standard offpage *
  page177_i1
#ISCELL
  mstr_symbols p3v3 *
  page177_i10
#CELL
  dev_discrete cap_a *
  page177_i20
#CELL
  mstr_discrete res *
  page177_i3
#ISCELL
  mstr_symbols gnd *
  page177_i30
#CELL
  mstr_discrete led *
  page177_i31
#CELL
  mstr_discrete res *
  page177_i33
#ISCELL
  mstr_symbols p5v_stby *
  page177_i36
#ISCELL
  mstr_standard offpage *
  page177_i4
#CELL
  mstr_discrete led *
  page177_i42
#CELL
  mstr_discrete res *
  page177_i43
#ISCELL
  mstr_symbols p3v3 *
  page177_i45
#ISCELL
  mstr_symbols gnd *
  page177_i46
#CELL
  mstr_discrete res *
  page177_i6
#CELL
  mstr_ttl ttl1g08 *
  page177_i70
#CELL
  mstr_discrete led *
  page177_i71
#CELL
  mstr_discrete res *
  page177_i72
#ISCELL
  mstr_symbols gnd *
  page177_i74
#CELL
  mstr_discrete res *
  page177_i76
#ISCELL
  mstr_symbols p3v3_stby *
  page177_i77
#ISCELL
  mstr_symbols p3v3_stby *
  page177_i78
#CELL
  mstr_discrete fet_n_dual *
  page177_i79
#CELL
  mstr_discrete res *
  page177_i8
#CELL
  mstr_discrete fet_n_dual *
  page177_i80
#ISCELL
  mstr_symbols p3v3_stby *
  page177_i81
#CELL
  mstr_discrete res *
  page177_i82
#ISCELL
  mstr_symbols gnd *
  page177_i83
#ISCELL
  mstr_standard offpage *
  page177_i84
#ISCELL
  mstr_symbols p3v3 *
  page177_i85
#CELL
  mstr_discrete res *
  page177_i9
